(kicad_pcb
	(version 20260206)
	(generator "pcbnew")
	(generator_version "10.0")
	(general
		(thickness 1.6)
		(legacy_teardrops no)
	)
	(paper "A4")
	(title_block
		(title "Bryce Canyon_IOM_IOC_16318-2_OCP.brd")
		(comment 1 "Bryce Canyon / footprint 522 of 1605 (EXT1), pads 1-43 of 43")
	)
	(layers
		(0 "F.Cu" signal "TOP")
		(4 "In1.Cu" signal "L2GND")
		(6 "In2.Cu" signal "L3")
		(8 "In3.Cu" signal "L4VCC")
		(10 "In4.Cu" signal "L5VCC")
		(12 "In5.Cu" signal "L6")
		(14 "In6.Cu" signal "L7GND")
		(2 "B.Cu" signal "BOTTOM")
		(9 "F.Adhes" user "F.Adhesive")
		(11 "B.Adhes" user "B.Adhesive")
		(13 "F.Paste" user "Package Geometry/Pastemask Top")
		(15 "B.Paste" user "Package Geometry/Pastemask Bottom")
		(5 "F.SilkS" user "Ref Des/Silkscreen Top")
		(7 "B.SilkS" user "Ref Des/Silkscreen Bottom")
		(1 "F.Mask" user "Board Geometry/Soldermask Top")
		(3 "B.Mask" user "Board Geometry/Soldermask Bottom")
		(17 "Dwgs.User" user "User.Drawings")
		(19 "Cmts.User" user "User.Comments")
		(21 "Eco1.User" user "User.Eco1")
		(23 "Eco2.User" user "User.Eco2")
		(25 "Edge.Cuts" user "Board Geometry/Outline")
		(27 "Margin" user)
		(31 "F.CrtYd" user "Package Geometry/Place Bound Top")
		(29 "B.CrtYd" user "Package Geometry/Place Bound Bottom")
		(35 "F.Fab" user "Ref Des/Assembly Top")
		(33 "B.Fab" user "Ref Des/Assembly Bottom")
	)
	(footprint ""
		(layer "F.Cu")
		(at 179.999894 -14.699996)
		(property "Reference" "EXT1"
			(at 0 0 0)
			(layer "F.SilkS")
			(hide yes)
			(effects
				(font
					(size 1.27 1.27)
				)
			)
		)
		(property "Value" "MINI-SAS-36P-7-GP"
			(at -9.3345 2.159 0)
			(unlocked yes)
			(layer "F.Fab")
			(hide yes)
			(effects
				(font
					(size 1.016 1.016)
					(thickness 0.1524)
				)
			)
		)
		(property "Device Type" "PREFIT-42P-131384H522"
			(at -9.3345 0.635 0)
			(unlocked yes)
			(layer "F.Fab")
			(hide yes)
			(effects
				(font
					(size 1.016 1.016)
					(thickness 0.1524)
				)
			)
		)
		(duplicate_pad_numbers_are_jumpers no)
		(pad "A1" thru_hole circle
			(at -2.999994 -4.400042)
			(size 0.7366 0.7366)
			(drill 0.369824)
			(layers "*.Cu" "*.Mask")
			(remove_unused_layers no)
			(net "ZDEF_EXTA_TP_A1")
			(clearance 0.1778)
			(thermal_gap 0.1778)
		)
		(pad "A2" thru_hole circle
			(at -2.249932 -2.999994)
			(size 0.7366 0.7366)
			(drill 0.369824)
			(layers "*.Cu" "*.Mask")
			(remove_unused_layers no)
			(net "ZDEF_EXTA_TP_A2")
			(clearance 0.1778)
			(thermal_gap 0.1778)
		)
		(pad "A3" thru_hole circle
			(at -1.500124 -3.700018)
			(size 0.7366 0.7366)
			(drill 0.369824)
			(layers "*.Cu" "*.Mask")
			(remove_unused_layers no)
			(net "GND")
			(clearance 0.1778)
			(thermal_gap 0.1778)
		)
		(pad "A4" thru_hole circle
			(at -0.749808 -4.400042)
			(size 0.7366 0.7366)
			(drill 0.369824)
			(layers "*.Cu" "*.Mask")
			(remove_unused_layers no)
			(net "PHY_CON_A_TO_IOC_1_DP_C")
			(clearance 0.1778)
			(thermal_gap 0.1778)
		)
		(pad "A5" thru_hole circle
			(at 0 -2.999994)
			(size 0.7366 0.7366)
			(drill 0.369824)
			(layers "*.Cu" "*.Mask")
			(remove_unused_layers no)
			(net "PHY_CON_A_TO_IOC_1_DN_C")
			(clearance 0.1778)
			(thermal_gap 0.1778)
		)
		(pad "A6" thru_hole circle
			(at 0.749808 -3.700018)
			(size 0.7366 0.7366)
			(drill 0.369824)
			(layers "*.Cu" "*.Mask")
			(remove_unused_layers no)
			(net "GND")
			(clearance 0.1778)
			(thermal_gap 0.1778)
		)
		(pad "A7" thru_hole circle
			(at 1.500124 -4.400042)
			(size 0.7366 0.7366)
			(drill 0.369824)
			(layers "*.Cu" "*.Mask")
			(remove_unused_layers no)
			(net "PHY_CON_A_TO_IOC_0_DP_C")
			(clearance 0.1778)
			(thermal_gap 0.1778)
		)
		(pad "A8" thru_hole circle
			(at 2.250186 -2.999994)
			(size 0.7366 0.7366)
			(drill 0.369824)
			(layers "*.Cu" "*.Mask")
			(remove_unused_layers no)
			(net "PHY_CON_A_TO_IOC_0_DN_C")
			(clearance 0.1778)
			(thermal_gap 0.1778)
		)
		(pad "A9" thru_hole circle
			(at 2.999994 -3.700018)
			(size 0.7366 0.7366)
			(drill 0.369824)
			(layers "*.Cu" "*.Mask")
			(remove_unused_layers no)
			(net "GND")
			(clearance 0.1778)
			(thermal_gap 0.1778)
		)
		(pad "B1" thru_hole circle
			(at -2.999994 -8.199882)
			(size 0.7366 0.7366)
			(drill 0.369824)
			(layers "*.Cu" "*.Mask")
			(remove_unused_layers no)
			(net "ZDEF_EXTA_TP_B1")
			(clearance 0.1778)
			(thermal_gap 0.1778)
		)
		(pad "B2" thru_hole circle
			(at -2.249932 -6.800088)
			(size 0.7366 0.7366)
			(drill 0.369824)
			(layers "*.Cu" "*.Mask")
			(remove_unused_layers no)
			(net "ZDEF_EXTA_TP_B2")
			(clearance 0.1778)
			(thermal_gap 0.1778)
		)
		(pad "B3" thru_hole circle
			(at -1.500124 -7.500112)
			(size 0.7366 0.7366)
			(drill 0.369824)
			(layers "*.Cu" "*.Mask")
			(remove_unused_layers no)
			(net "GND")
			(clearance 0.1778)
			(thermal_gap 0.1778)
		)
		(pad "B4" thru_hole circle
			(at -0.749808 -8.199882)
			(size 0.7366 0.7366)
			(drill 0.369824)
			(layers "*.Cu" "*.Mask")
			(remove_unused_layers no)
			(net "PHY_CON_A_TO_IOC_3_DP_C")
			(clearance 0.1778)
			(thermal_gap 0.1778)
		)
		(pad "B5" thru_hole circle
			(at 0 -6.800088)
			(size 0.7366 0.7366)
			(drill 0.369824)
			(layers "*.Cu" "*.Mask")
			(remove_unused_layers no)
			(net "PHY_CON_A_TO_IOC_3_DN_C")
			(clearance 0.1778)
			(thermal_gap 0.1778)
		)
		(pad "B6" thru_hole circle
			(at 0.749808 -7.500112)
			(size 0.7366 0.7366)
			(drill 0.369824)
			(layers "*.Cu" "*.Mask")
			(remove_unused_layers no)
			(net "GND")
			(clearance 0.1778)
			(thermal_gap 0.1778)
		)
		(pad "B7" thru_hole circle
			(at 1.500124 -8.199882)
			(size 0.7366 0.7366)
			(drill 0.369824)
			(layers "*.Cu" "*.Mask")
			(remove_unused_layers no)
			(net "PHY_CON_A_TO_IOC_2_DP_C")
			(clearance 0.1778)
			(thermal_gap 0.1778)
		)
		(pad "B8" thru_hole circle
			(at 2.250186 -6.800088)
			(size 0.7366 0.7366)
			(drill 0.369824)
			(layers "*.Cu" "*.Mask")
			(remove_unused_layers no)
			(net "PHY_CON_A_TO_IOC_2_DN_C")
			(clearance 0.1778)
			(thermal_gap 0.1778)
		)
		(pad "B9" thru_hole circle
			(at 2.999994 -7.500112)
			(size 0.7366 0.7366)
			(drill 0.369824)
			(layers "*.Cu" "*.Mask")
			(remove_unused_layers no)
			(net "GND")
			(clearance 0.1778)
			(thermal_gap 0.1778)
		)
		(pad "C1" thru_hole circle
			(at -2.999994 -11.999976)
			(size 0.7366 0.7366)
			(drill 0.369824)
			(layers "*.Cu" "*.Mask")
			(remove_unused_layers no)
			(net "ZDEF_EXTA_TP_C1")
			(clearance 0.1778)
			(thermal_gap 0.1778)
		)
		(pad "C2" thru_hole circle
			(at -2.249932 -10.599928)
			(size 0.7366 0.7366)
			(drill 0.369824)
			(layers "*.Cu" "*.Mask")
			(remove_unused_layers no)
			(net "ZDEF_EXTA_TP_C2")
			(clearance 0.1778)
			(thermal_gap 0.1778)
		)
		(pad "C3" thru_hole circle
			(at -1.500124 -11.299952)
			(size 0.7366 0.7366)
			(drill 0.369824)
			(layers "*.Cu" "*.Mask")
			(remove_unused_layers no)
			(net "GND")
			(clearance 0.1778)
			(thermal_gap 0.1778)
		)
		(pad "C4" thru_hole circle
			(at -0.749808 -11.999976)
			(size 0.7366 0.7366)
			(drill 0.369824)
			(layers "*.Cu" "*.Mask")
			(remove_unused_layers no)
			(net "PHY_IOC_TO_CON_A_1_DP")
			(clearance 0.1778)
			(thermal_gap 0.1778)
		)
		(pad "C5" thru_hole circle
			(at 0 -10.599928)
			(size 0.7366 0.7366)
			(drill 0.369824)
			(layers "*.Cu" "*.Mask")
			(remove_unused_layers no)
			(net "PHY_IOC_TO_CON_A_1_DN")
			(clearance 0.1778)
			(thermal_gap 0.1778)
		)
		(pad "C6" thru_hole circle
			(at 0.749808 -11.299952)
			(size 0.7366 0.7366)
			(drill 0.369824)
			(layers "*.Cu" "*.Mask")
			(remove_unused_layers no)
			(net "GND")
			(clearance 0.1778)
			(thermal_gap 0.1778)
		)
		(pad "C7" thru_hole circle
			(at 1.500124 -11.999976)
			(size 0.7366 0.7366)
			(drill 0.369824)
			(layers "*.Cu" "*.Mask")
			(remove_unused_layers no)
			(net "PHY_IOC_TO_CON_A_0_DP")
			(clearance 0.1778)
			(thermal_gap 0.1778)
		)
		(pad "C8" thru_hole circle
			(at 2.250186 -10.599928)
			(size 0.7366 0.7366)
			(drill 0.369824)
			(layers "*.Cu" "*.Mask")
			(remove_unused_layers no)
			(net "PHY_IOC_TO_CON_A_0_DN")
			(clearance 0.1778)
			(thermal_gap 0.1778)
		)
		(pad "C9" thru_hole circle
			(at 2.999994 -11.299952)
			(size 0.7366 0.7366)
			(drill 0.369824)
			(layers "*.Cu" "*.Mask")
			(remove_unused_layers no)
			(net "GND")
			(clearance 0.1778)
			(thermal_gap 0.1778)
		)
		(pad "D1" thru_hole circle
			(at -2.999994 -15.80007)
			(size 0.7366 0.7366)
			(drill 0.369824)
			(layers "*.Cu" "*.Mask")
			(remove_unused_layers no)
			(net "ZDEF_EXTA_TP_D1")
			(clearance 0.1778)
			(thermal_gap 0.1778)
		)
		(pad "D2" thru_hole circle
			(at -2.249932 -14.400022)
			(size 0.7366 0.7366)
			(drill 0.369824)
			(layers "*.Cu" "*.Mask")
			(remove_unused_layers no)
			(net "ZDEF_EXTA_TP_D2")
			(clearance 0.1778)
			(thermal_gap 0.1778)
		)
		(pad "D3" thru_hole circle
			(at -1.500124 -15.100046)
			(size 0.7366 0.7366)
			(drill 0.369824)
			(layers "*.Cu" "*.Mask")
			(remove_unused_layers no)
			(net "GND")
			(clearance 0.1778)
			(thermal_gap 0.1778)
		)
		(pad "D4" thru_hole circle
			(at -0.749808 -15.80007)
			(size 0.7366 0.7366)
			(drill 0.369824)
			(layers "*.Cu" "*.Mask")
			(remove_unused_layers no)
			(net "PHY_IOC_TO_CON_A_3_DP")
			(clearance 0.1778)
			(thermal_gap 0.1778)
		)
		(pad "D5" thru_hole circle
			(at 0 -14.400022)
			(size 0.7366 0.7366)
			(drill 0.369824)
			(layers "*.Cu" "*.Mask")
			(remove_unused_layers no)
			(net "PHY_IOC_TO_CON_A_3_DN")
			(clearance 0.1778)
			(thermal_gap 0.1778)
		)
		(pad "D6" thru_hole circle
			(at 0.749808 -15.100046)
			(size 0.7366 0.7366)
			(drill 0.369824)
			(layers "*.Cu" "*.Mask")
			(remove_unused_layers no)
			(net "GND")
			(clearance 0.1778)
			(thermal_gap 0.1778)
		)
		(pad "D7" thru_hole circle
			(at 1.500124 -15.80007)
			(size 0.7366 0.7366)
			(drill 0.369824)
			(layers "*.Cu" "*.Mask")
			(remove_unused_layers no)
			(net "PHY_IOC_TO_CON_A_2_DP")
			(clearance 0.1778)
			(thermal_gap 0.1778)
		)
		(pad "D8" thru_hole circle
			(at 2.250186 -14.400022)
			(size 0.7366 0.7366)
			(drill 0.369824)
			(layers "*.Cu" "*.Mask")
			(remove_unused_layers no)
			(net "PHY_IOC_TO_CON_A_2_DN")
			(clearance 0.1778)
			(thermal_gap 0.1778)
		)
		(pad "D9" thru_hole circle
			(at 2.999994 -15.100046)
			(size 0.7366 0.7366)
			(drill 0.369824)
			(layers "*.Cu" "*.Mask")
			(remove_unused_layers no)
			(net "GND")
			(clearance 0.1778)
			(thermal_gap 0.1778)
		)
		(pad "G1" thru_hole circle
			(at -5.500116 9.61009)
			(size 0.9144 0.9144)
			(drill 0.569976)
			(layers "*.Cu" "*.Mask")
			(remove_unused_layers no)
			(net "EXT1_CONN_GND")
			(clearance 0.1905)
			(thermal_gap 0.1905)
		)
		(pad "G2" thru_hole circle
			(at 5.500116 9.61009)
			(size 0.9144 0.9144)
			(drill 0.569976)
			(layers "*.Cu" "*.Mask")
			(remove_unused_layers no)
			(net "EXT1_CONN_GND")
			(clearance 0.1905)
			(thermal_gap 0.1905)
		)
		(pad "G3" thru_hole circle
			(at -5.500116 -3.700018)
			(size 0.9144 0.9144)
			(drill 0.569976)
			(layers "*.Cu" "*.Mask")
			(remove_unused_layers no)
			(net "EXT1_CONN_GND")
			(clearance 0.1905)
			(thermal_gap 0.1905)
		)
		(pad "G4" thru_hole circle
			(at 5.500116 -3.700018)
			(size 0.9144 0.9144)
			(drill 0.569976)
			(layers "*.Cu" "*.Mask")
			(remove_unused_layers no)
			(net "EXT1_CONN_GND")
			(clearance 0.1905)
			(thermal_gap 0.1905)
		)
		(pad "G5" thru_hole circle
			(at -1.500124 -17.509998)
			(size 0.9144 0.9144)
			(drill 0.569976)
			(layers "*.Cu" "*.Mask")
			(remove_unused_layers no)
			(net "EXT1_CONN_GND")
			(clearance 0.1905)
			(thermal_gap 0.1905)
		)
		(pad "G6" thru_hole circle
			(at 2.999994 -17.509998)
			(size 0.9144 0.9144)
			(drill 0.569976)
			(layers "*.Cu" "*.Mask")
			(remove_unused_layers no)
			(net "EXT1_CONN_GND")
			(clearance 0.1905)
			(thermal_gap 0.1905)
		)
		(pad "G7" thru_hole circle
			(at 0 0)
			(size 3.81 3.81)
			(drill 2.2098)
			(layers "*.Cu" "*.Mask")
			(remove_unused_layers no)
			(net "EXT1_CONN_GND")
			(clearance -0.2921)
			(thermal_gap 0.3048)
			(padstack
				(mode front_inner_back)
				(layer "Inner"
					(shape circle)
					(size 2.6162 2.6162)
					(clearance 0.3048)
				)
				(layer "B.Cu"
					(shape circle)
					(size 3.81 3.81)
					(clearance -0.2921)
				)
			)
		)
	)
)
